# SCM (Grand Teton) — schematic netlist excerpt (pin names and nets, part order shuffled) for the footprints in the layout excerpt that follows; sources: Cadence DE-HDL packaged netlist, KiCad conversion of 12092022_DA0F0TMDCD0_F0T_Management_Board_D_brd_V3_OCP.brd

C326  Q_CAP  470PF 50V 10% X7R  pkg 0402  page 49 : A = PWR_LED_BUF_N_R ; B = GND
R325  Q_RES  1K 1% CHIP  pkg 0402LF  page 20 : A = P0V6_DDR_VREF_AUX ; B = GND

(kicad_pcb
	(version 20260206)
	(generator "pcbnew")
	(generator_version "10.0")
	(general
		(thickness 1.6)
		(legacy_teardrops no)
	)
	(paper "A4")
	(title_block
		(title "12092022_DA0F0TMDCD0_F0T_Management_Board_D_brd_V3_OCP.brd")
		(comment 1 "Grand Teton / footprints 777-778 of 1440")
	)
	(layers
		(0 "F.Cu" signal "TOP")
		(4 "In1.Cu" signal "GND")
		(6 "In2.Cu" signal "IN1")
		(8 "In3.Cu" signal "GND1")
		(10 "In4.Cu" signal "IN2")
		(12 "In5.Cu" signal "VCC")
		(14 "In6.Cu" signal "VCC1")
		(16 "In7.Cu" signal "IN3")
		(18 "In8.Cu" signal "GND2")
		(20 "In9.Cu" signal "IN4")
		(22 "In10.Cu" signal "GND3")
		(2 "B.Cu" signal "BOTTOM")
		(9 "F.Adhes" user "F.Adhesive")
		(11 "B.Adhes" user "B.Adhesive")
		(13 "F.Paste" user "Package Geometry/Pastemask Top")
		(15 "B.Paste" user "Package Geometry/Pastemask Bottom")
		(5 "F.SilkS" user "Ref Des/Silkscreen Top")
		(7 "B.SilkS" user "Ref Des/Silkscreen Bottom")
		(1 "F.Mask" user "Board Geometry/Soldermask Top")
		(3 "B.Mask" user "Board Geometry/Soldermask Bottom")
		(17 "Dwgs.User" user "User.Drawings")
		(19 "Cmts.User" user "User.Comments")
		(21 "Eco1.User" user "User.Eco1")
		(23 "Eco2.User" user "User.Eco2")
		(25 "Edge.Cuts" user "Board Geometry/Outline")
		(27 "Margin" user)
		(31 "F.CrtYd" user "Package Geometry/Place Bound Top")
		(29 "B.CrtYd" user "Package Geometry/Place Bound Bottom")
		(35 "F.Fab" user "Ref Des/Assembly Top")
		(33 "B.Fab" user "Ref Des/Assembly Bottom")
	)
	(footprint ""
		(layer "B.Cu")
		(at 15.113 -20.447 90)
		(property "Reference" "C326"
			(at 0 0 90)
			(layer "B.SilkS")
			(hide yes)
			(effects
				(font
					(size 1.27 1.27)
				)
				(justify mirror)
			)
		)
		(property "Value" ""
			(at 0 0 90)
			(layer "B.Fab")
			(effects
				(font
					(size 1.27 1.27)
				)
				(justify mirror)
			)
		)
		(duplicate_pad_numbers_are_jumpers no)
		(fp_line
			(start 0.7874 -0.4064)
			(end -0.7874 -0.4064)
			(stroke
				(width 0.1524)
				(type default)
			)
			(layer "B.SilkS")
		)
		(fp_line
			(start -0.7874 -0.4064)
			(end -0.7874 0.4064)
			(stroke
				(width 0.1524)
				(type default)
			)
			(layer "B.SilkS")
		)
		(fp_line
			(start 0.7874 0.4064)
			(end 0.7874 -0.4064)
			(stroke
				(width 0.1524)
				(type default)
			)
			(layer "B.SilkS")
		)
		(fp_line
			(start -0.7874 0.4064)
			(end 0.7874 0.4064)
			(stroke
				(width 0.1524)
				(type default)
			)
			(layer "B.SilkS")
		)
		(fp_line
			(start 0.67945 -0.305054)
			(end 0.12065 -0.305054)
			(stroke
				(width 0.1)
				(type default)
			)
			(layer "B.Fab")
		)
		(fp_line
			(start 0.12065 -0.305054)
			(end 0.12065 -0.2794)
			(stroke
				(width 0.1)
				(type default)
			)
			(layer "B.Fab")
		)
		(fp_line
			(start -0.12065 -0.3048)
			(end -0.67945 -0.3048)
			(stroke
				(width 0.1)
				(type default)
			)
			(layer "B.Fab")
		)
		(fp_line
			(start -0.67945 -0.3048)
			(end -0.67945 0.3048)
			(stroke
				(width 0.1)
				(type default)
			)
			(layer "B.Fab")
		)
		(fp_line
			(start 0.12065 -0.2794)
			(end -0.12065 -0.2794)
			(stroke
				(width 0.1)
				(type default)
			)
			(layer "B.Fab")
		)
		(fp_line
			(start -0.12065 -0.2794)
			(end -0.12065 -0.3048)
			(stroke
				(width 0.1)
				(type default)
			)
			(layer "B.Fab")
		)
		(fp_line
			(start 0.12065 0.2794)
			(end 0.12065 0.3048)
			(stroke
				(width 0.1)
				(type default)
			)
			(layer "B.Fab")
		)
		(fp_line
			(start -0.120396 0.2794)
			(end 0.12065 0.2794)
			(stroke
				(width 0.1)
				(type default)
			)
			(layer "B.Fab")
		)
		(fp_line
			(start 0.67945 0.3048)
			(end 0.67945 -0.305054)
			(stroke
				(width 0.1)
				(type default)
			)
			(layer "B.Fab")
		)
		(fp_line
			(start 0.12065 0.3048)
			(end 0.67945 0.3048)
			(stroke
				(width 0.1)
				(type default)
			)
			(layer "B.Fab")
		)
		(fp_line
			(start -0.120396 0.3048)
			(end -0.120396 0.2794)
			(stroke
				(width 0.1)
				(type default)
			)
			(layer "B.Fab")
		)
		(fp_line
			(start -0.67945 0.3048)
			(end -0.120396 0.3048)
			(stroke
				(width 0.1)
				(type default)
			)
			(layer "B.Fab")
		)
		(pad "1" smd circle
			(at 0.40005 0 270)
			(size 0 0)
			(layers "B.Cu" "B.Mask" "B.Paste")
			(net "PWR_LED_BUF_N_R")
		)
		(pad "2" smd circle
			(at -0.40005 0 270)
			(size 0 0)
			(layers "B.Cu" "B.Mask" "B.Paste")
			(net "GND")
		)
	)
	(footprint ""
		(layer "B.Cu")
		(at 84.08924 -53.413152 180)
		(property "Reference" "R325"
			(at 0 0 0)
			(layer "B.SilkS")
			(hide yes)
			(effects
				(font
					(size 1.27 1.27)
				)
				(justify mirror)
			)
		)
		(property "Value" ""
			(at 0 0 0)
			(layer "B.Fab")
			(effects
				(font
					(size 1.27 1.27)
				)
				(justify mirror)
			)
		)
		(duplicate_pad_numbers_are_jumpers no)
		(fp_line
			(start 0.7874 0.4064)
			(end 0.7874 -0.4064)
			(stroke
				(width 0.1524)
				(type default)
			)
			(layer "B.SilkS")
		)
		(fp_line
			(start 0.7874 -0.4064)
			(end -0.7874 -0.4064)
			(stroke
				(width 0.1524)
				(type default)
			)
			(layer "B.SilkS")
		)
		(fp_line
			(start -0.7874 0.4064)
			(end 0.7874 0.4064)
			(stroke
				(width 0.1524)
				(type default)
			)
			(layer "B.SilkS")
		)
		(fp_line
			(start -0.7874 -0.4064)
			(end -0.7874 0.4064)
			(stroke
				(width 0.1524)
				(type default)
			)
			(layer "B.SilkS")
		)
		(fp_line
			(start 0.67945 0.3048)
			(end 0.67945 -0.305054)
			(stroke
				(width 0.1)
				(type default)
			)
			(layer "B.Fab")
		)
		(fp_line
			(start 0.67945 -0.305054)
			(end 0.12065 -0.305054)
			(stroke
				(width 0.1)
				(type default)
			)
			(layer "B.Fab")
		)
		(fp_line
			(start 0.12065 0.3048)
			(end 0.67945 0.3048)
			(stroke
				(width 0.1)
				(type default)
			)
			(layer "B.Fab")
		)
		(fp_line
			(start 0.12065 0.2794)
			(end 0.12065 0.3048)
			(stroke
				(width 0.1)
				(type default)
			)
			(layer "B.Fab")
		)
		(fp_line
			(start 0.12065 -0.2794)
			(end -0.12065 -0.2794)
			(stroke
				(width 0.1)
				(type default)
			)
			(layer "B.Fab")
		)
		(fp_line
			(start 0.12065 -0.305054)
			(end 0.12065 -0.2794)
			(stroke
				(width 0.1)
				(type default)
			)
			(layer "B.Fab")
		)
		(fp_line
			(start -0.120396 0.3048)
			(end -0.120396 0.2794)
			(stroke
				(width 0.1)
				(type default)
			)
			(layer "B.Fab")
		)
		(fp_line
			(start -0.120396 0.2794)
			(end 0.12065 0.2794)
			(stroke
				(width 0.1)
				(type default)
			)
			(layer "B.Fab")
		)
		(fp_line
			(start -0.12065 -0.2794)
			(end -0.12065 -0.3048)
			(stroke
				(width 0.1)
				(type default)
			)
			(layer "B.Fab")
		)
		(fp_line
			(start -0.12065 -0.3048)
			(end -0.67945 -0.3048)
			(stroke
				(width 0.1)
				(type default)
			)
			(layer "B.Fab")
		)
		(fp_line
			(start -0.67945 0.3048)
			(end -0.120396 0.3048)
			(stroke
				(width 0.1)
				(type default)
			)
			(layer "B.Fab")
		)
		(fp_line
			(start -0.67945 -0.3048)
			(end -0.67945 0.3048)
			(stroke
				(width 0.1)
				(type default)
			)
			(layer "B.Fab")
		)
		(pad "1" smd circle
			(at 0.40005 0)
			(size 0 0)
			(layers "B.Cu" "B.Mask" "B.Paste")
			(net "P0V6_DDR_VREF_AUX")
		)
		(pad "2" smd circle
			(at -0.40005 0)
			(size 0 0)
			(layers "B.Cu" "B.Mask" "B.Paste")
			(net "GND")
		)
	)
)
